# BASEBOARD_FAB2 (Tioga Pass) — schematic netlist excerpt (pin names and nets, part order shuffled) for the footprints in the layout excerpt that follows; sources: Cadence DE-HDL packaged netlist, KiCad conversion of Wiwynn_Tioga_Pass_MB.brd

R4E18  RES  100.0 1% CHIP  pkg 0402  page 204 : A = VSENSE_PVCCIN_CPU0_N ; B = GND
R8P1  RES  49.9 1% CHIP  pkg 0402  page 90 : A = PD_CPU1_TEST14 ; B = GND
C5G101  CAP_A  22.0UF 4V 20% X6S  pkg 0603V  page 243 : A = PVDDQ_KLM ; B = GND

(kicad_pcb
	(version 20260206)
	(generator "pcbnew")
	(generator_version "10.0")
	(general
		(thickness 1.6)
		(legacy_teardrops no)
	)
	(paper "A4")
	(title_block
		(title "Wiwynn_Tioga_Pass_MB.brd")
		(comment 1 "Tioga Pass / footprints 2549-2551 of 4770")
	)
	(layers
		(0 "F.Cu" signal "TOP")
		(4 "In1.Cu" signal "L2GND")
		(6 "In2.Cu" signal "L3")
		(8 "In3.Cu" signal "L4GND")
		(10 "In4.Cu" signal "L5")
		(12 "In5.Cu" signal "L6GND")
		(14 "In6.Cu" signal "L7VCC")
		(16 "In7.Cu" signal "L8VCC")
		(18 "In8.Cu" signal "L9GND")
		(20 "In9.Cu" signal "L10")
		(22 "In10.Cu" signal "L11GND")
		(24 "In11.Cu" signal "L12")
		(26 "In12.Cu" signal "L13GND")
		(2 "B.Cu" signal "BOTTOM")
		(9 "F.Adhes" user "F.Adhesive")
		(11 "B.Adhes" user "B.Adhesive")
		(13 "F.Paste" user "Package Geometry/Pastemask Top")
		(15 "B.Paste" user "Package Geometry/Pastemask Bottom")
		(5 "F.SilkS" user "Ref Des/Silkscreen Top")
		(7 "B.SilkS" user "Ref Des/Silkscreen Bottom")
		(1 "F.Mask" user "Board Geometry/Soldermask Top")
		(3 "B.Mask" user "Board Geometry/Soldermask Bottom")
		(17 "Dwgs.User" user "User.Drawings")
		(19 "Cmts.User" user "User.Comments")
		(21 "Eco1.User" user "User.Eco1")
		(23 "Eco2.User" user "User.Eco2")
		(25 "Edge.Cuts" user "Board Geometry/Outline")
		(27 "Margin" user)
		(31 "F.CrtYd" user "Package Geometry/Place Bound Top")
		(29 "B.CrtYd" user "Package Geometry/Place Bound Bottom")
		(35 "F.Fab" user "Ref Des/Assembly Top")
		(33 "B.Fab" user "Ref Des/Assembly Bottom")
	)
	(footprint ""
		(layer "B.Cu")
		(at 80.153002 -87.632286 -90)
		(property "Reference" "R8P1"
			(at 0 0 90)
			(layer "B.SilkS")
			(hide yes)
			(effects
				(font
					(size 1.27 1.27)
				)
				(justify mirror)
			)
		)
		(property "Value" ""
			(at 0 0 90)
			(layer "B.Fab")
			(effects
				(font
					(size 1.27 1.27)
				)
				(justify mirror)
			)
		)
		(duplicate_pad_numbers_are_jumpers no)
		(fp_poly
			(pts
				(xy 0.2794 -0.1016) (xy -0.2794 -0.1016) (xy -0.2794 0.9906) (xy 0.2794 0.9906)
			)
			(stroke
				(width 0)
				(type default)
			)
			(fill no)
			(layer "B.CrtYd")
		)
		(fp_line
			(start -0.2794 0.9906)
			(end -0.2794 -0.1016)
			(stroke
				(width 0.1)
				(type default)
			)
			(layer "B.Fab")
		)
		(fp_line
			(start 0.2794 0.9906)
			(end -0.2794 0.9906)
			(stroke
				(width 0.1)
				(type default)
			)
			(layer "B.Fab")
		)
		(fp_line
			(start -0.2794 -0.1016)
			(end 0.2794 -0.1016)
			(stroke
				(width 0.1)
				(type default)
			)
			(layer "B.Fab")
		)
		(fp_line
			(start 0.2794 -0.1016)
			(end 0.2794 0.9906)
			(stroke
				(width 0.1)
				(type default)
			)
			(layer "B.Fab")
		)
		(pad "1" smd rect
			(at 0 0 90)
			(size 0.508 0.508)
			(layers "B.Cu" "B.Mask" "B.Paste")
			(net "PD_CPU1_TEST14")
		)
		(pad "2" smd rect
			(at 0 0.889 90)
			(size 0.508 0.508)
			(layers "B.Cu" "B.Mask" "B.Paste")
			(net "GND")
		)
		(zone
			(layer "B.Cu")
			(hatch none 0.5)
			(connect_pads
				(clearance 0)
			)
			(min_thickness 0.25)
			(keepout
				(tracks not_allowed)
				(vias allowed)
				(pads allowed)
				(copperpour not_allowed)
				(footprints allowed)
			)
			(placement
				(enabled no)
				(sheetname "")
			)
			(fill
				(thermal_gap 0.5)
				(thermal_bridge_width 0.5)
				(island_removal_mode 0)
			)
			(polygon
				(pts
					(xy 79.518002 -87.378286) (xy 79.518002 -87.886286) (xy 79.899002 -87.886286) (xy 79.899002 -87.378286)
				)
			)
		)
		(zone
			(layer "B.Cu")
			(hatch none 0.5)
			(connect_pads
				(clearance 0)
			)
			(min_thickness 0.25)
			(keepout
				(tracks allowed)
				(vias not_allowed)
				(pads allowed)
				(copperpour not_allowed)
				(footprints allowed)
			)
			(placement
				(enabled no)
				(sheetname "")
			)
			(fill
				(thermal_gap 0.5)
				(thermal_bridge_width 0.5)
				(island_removal_mode 0)
			)
			(polygon
				(pts
					(xy 79.899002 -87.378286) (xy 79.899002 -87.886286) (xy 79.518002 -87.886286) (xy 79.518002 -87.378286)
				)
			)
		)
	)
	(footprint ""
		(layer "B.Cu")
		(at 229.3747 -64.6303 180)
		(property "Reference" "R4E18"
			(at 0 0 0)
			(layer "B.SilkS")
			(hide yes)
			(effects
				(font
					(size 1.27 1.27)
				)
				(justify mirror)
			)
		)
		(property "Value" ""
			(at 0 0 0)
			(layer "B.Fab")
			(effects
				(font
					(size 1.27 1.27)
				)
				(justify mirror)
			)
		)
		(duplicate_pad_numbers_are_jumpers no)
		(fp_poly
			(pts
				(xy 0.2794 -0.1016) (xy -0.2794 -0.1016) (xy -0.2794 0.9906) (xy 0.2794 0.9906)
			)
			(stroke
				(width 0)
				(type default)
			)
			(fill no)
			(layer "B.CrtYd")
		)
		(fp_line
			(start 0.2794 0.9906)
			(end -0.2794 0.9906)
			(stroke
				(width 0.1)
				(type default)
			)
			(layer "B.Fab")
		)
		(fp_line
			(start 0.2794 -0.1016)
			(end 0.2794 0.9906)
			(stroke
				(width 0.1)
				(type default)
			)
			(layer "B.Fab")
		)
		(fp_line
			(start -0.2794 0.9906)
			(end -0.2794 -0.1016)
			(stroke
				(width 0.1)
				(type default)
			)
			(layer "B.Fab")
		)
		(fp_line
			(start -0.2794 -0.1016)
			(end 0.2794 -0.1016)
			(stroke
				(width 0.1)
				(type default)
			)
			(layer "B.Fab")
		)
		(pad "1" smd rect
			(at 0 0)
			(size 0.508 0.508)
			(layers "B.Cu" "B.Mask" "B.Paste")
			(net "VSENSE_PVCCIN_CPU0_N")
		)
		(pad "2" smd rect
			(at 0 0.889)
			(size 0.508 0.508)
			(layers "B.Cu" "B.Mask" "B.Paste")
			(net "GND")
		)
		(zone
			(layer "B.Cu")
			(hatch none 0.5)
			(connect_pads
				(clearance 0)
			)
			(min_thickness 0.25)
			(keepout
				(tracks not_allowed)
				(vias allowed)
				(pads allowed)
				(copperpour not_allowed)
				(footprints allowed)
			)
			(placement
				(enabled no)
				(sheetname "")
			)
			(fill
				(thermal_gap 0.5)
				(thermal_bridge_width 0.5)
				(island_removal_mode 0)
			)
			(polygon
				(pts
					(xy 229.1207 -65.2653) (xy 229.6287 -65.2653) (xy 229.6287 -64.8843) (xy 229.1207 -64.8843)
				)
			)
		)
		(zone
			(layer "B.Cu")
			(hatch none 0.5)
			(connect_pads
				(clearance 0)
			)
			(min_thickness 0.25)
			(keepout
				(tracks allowed)
				(vias not_allowed)
				(pads allowed)
				(copperpour not_allowed)
				(footprints allowed)
			)
			(placement
				(enabled no)
				(sheetname "")
			)
			(fill
				(thermal_gap 0.5)
				(thermal_bridge_width 0.5)
				(island_removal_mode 0)
			)
			(polygon
				(pts
					(xy 229.1207 -64.8843) (xy 229.6287 -64.8843) (xy 229.6287 -65.2653) (xy 229.1207 -65.2653)
				)
			)
		)
	)
	(footprint ""
		(layer "B.Cu")
		(at 80.731868 -149.8092 -90)
		(property "Reference" "C5G101"
			(at -1.14681 0.76708 0)
			(unlocked yes)
			(layer "B.SilkS")
			(effects
				(font
					(size 0.7874 0.5842)
					(thickness 0.1524)
				)
				(justify mirror)
			)
		)
		(property "Value" ""
			(at 0 0 90)
			(layer "B.Fab")
			(effects
				(font
					(size 1.27 1.27)
				)
				(justify mirror)
			)
		)
		(duplicate_pad_numbers_are_jumpers no)
		(fp_rect
			(start 0.4953 1.6002)
			(end -0.4953 -0.2032)
			(stroke
				(width 0)
				(type default)
			)
			(fill no)
			(layer "B.CrtYd")
		)
		(fp_line
			(start -0.4953 1.6002)
			(end 0.4953 1.6002)
			(stroke
				(width 0.1)
				(type default)
			)
			(layer "B.Fab")
		)
		(fp_line
			(start 0.4953 1.6002)
			(end 0.4953 -0.2032)
			(stroke
				(width 0.1)
				(type default)
			)
			(layer "B.Fab")
		)
		(fp_line
			(start -0.4953 -0.2032)
			(end -0.4953 1.6002)
			(stroke
				(width 0.1)
				(type default)
			)
			(layer "B.Fab")
		)
		(fp_line
			(start 0.4953 -0.2032)
			(end -0.4953 -0.2032)
			(stroke
				(width 0.1)
				(type default)
			)
			(layer "B.Fab")
		)
		(pad "1" smd rect
			(at 0 0 90)
			(size 0.762 0.889)
			(layers "B.Cu" "B.Mask" "B.Paste")
			(net "PVDDQ_KLM")
		)
		(pad "2" smd rect
			(at 0 1.397 90)
			(size 0.762 0.889)
			(layers "B.Cu" "B.Mask" "B.Paste")
			(net "GND")
		)
		(zone
			(layer "B.Cu")
			(hatch none 0.5)
			(connect_pads
				(clearance 0)
			)
			(min_thickness 0.25)
			(keepout
				(tracks not_allowed)
				(vias allowed)
				(pads allowed)
				(copperpour not_allowed)
				(footprints allowed)
			)
			(placement
				(enabled no)
				(sheetname "")
			)
			(fill
				(thermal_gap 0.5)
				(thermal_bridge_width 0.5)
				(island_removal_mode 0)
			)
			(polygon
				(pts
					(xy 79.779368 -149.4282) (xy 80.287368 -149.4282) (xy 80.287368 -150.1902) (xy 79.779368 -150.1902)
				)
			)
		)
	)
)
